(kicad_pcb
	(version 20260206)
	(generator "pcbnew")
	(generator_version "10.0")
	(general
		(thickness 1.6)
		(legacy_teardrops no)
	)
	(paper "A4")
	(title_block
		(title "01162023_DA0F0TEBIF0_F0T_Expander_BD_F_brd_V02_OCP.brd")
		(comment 1 "Grand Teton / footprints 3918-3923 of 9728")
	)
	(layers
		(0 "F.Cu" signal "TOP")
		(4 "In1.Cu" signal "GND")
		(6 "In2.Cu" signal "VCC")
		(8 "In3.Cu" signal "VCC1")
		(10 "In4.Cu" signal "GND1")
		(12 "In5.Cu" signal "IN1")
		(14 "In6.Cu" signal "GND2")
		(16 "In7.Cu" signal "IN2")
		(18 "In8.Cu" signal "GND3")
		(20 "In9.Cu" signal "IN3")
		(22 "In10.Cu" signal "GND4")
		(24 "In11.Cu" signal "IN4")
		(26 "In12.Cu" signal "GND5")
		(28 "In13.Cu" signal "IN5")
		(30 "In14.Cu" signal "GND6")
		(32 "In15.Cu" signal "IN6")
		(34 "In16.Cu" signal "GND7")
		(2 "B.Cu" signal "BOTTOM")
		(9 "F.Adhes" user "F.Adhesive")
		(11 "B.Adhes" user "B.Adhesive")
		(13 "F.Paste" user "Package Geometry/Pastemask Top")
		(15 "B.Paste" user "Package Geometry/Pastemask Bottom")
		(5 "F.SilkS" user "Ref Des/Silkscreen Top")
		(7 "B.SilkS" user "Ref Des/Silkscreen Bottom")
		(1 "F.Mask" user "Board Geometry/Soldermask Top")
		(3 "B.Mask" user "Board Geometry/Soldermask Bottom")
		(17 "Dwgs.User" user "User.Drawings")
		(19 "Cmts.User" user "User.Comments")
		(21 "Eco1.User" user "User.Eco1")
		(23 "Eco2.User" user "User.Eco2")
		(25 "Edge.Cuts" user "Board Geometry/Outline")
		(27 "Margin" user)
		(31 "F.CrtYd" user "Package Geometry/Place Bound Top")
		(29 "B.CrtYd" user "Package Geometry/Place Bound Bottom")
		(35 "F.Fab" user "Ref Des/Assembly Top")
		(33 "B.Fab" user "Ref Des/Assembly Bottom")
	)
	(footprint ""
		(layer "F.Cu")
		(at 123.982226 -279.486868 -90)
		(property "Reference" "PR110"
			(at 0 0 270)
			(layer "F.SilkS")
			(hide yes)
			(effects
				(font
					(size 1.27 1.27)
				)
			)
		)
		(property "Value" ""
			(at 0 0 270)
			(layer "F.Fab")
			(effects
				(font
					(size 1.27 1.27)
				)
			)
		)
		(duplicate_pad_numbers_are_jumpers no)
		(fp_line
			(start -0.7874 0.4064)
			(end -0.7874 -0.4064)
			(stroke
				(width 0.1524)
				(type default)
			)
			(layer "F.SilkS")
		)
		(fp_line
			(start 0.7874 0.4064)
			(end -0.7874 0.4064)
			(stroke
				(width 0.1524)
				(type default)
			)
			(layer "F.SilkS")
		)
		(fp_line
			(start -0.7874 -0.4064)
			(end 0.7874 -0.4064)
			(stroke
				(width 0.1524)
				(type default)
			)
			(layer "F.SilkS")
		)
		(fp_line
			(start 0.7874 -0.4064)
			(end 0.7874 0.4064)
			(stroke
				(width 0.1524)
				(type default)
			)
			(layer "F.SilkS")
		)
		(fp_line
			(start -0.67945 0.3048)
			(end -0.67945 -0.305054)
			(stroke
				(width 0.1)
				(type default)
			)
			(layer "F.Fab")
		)
		(fp_line
			(start -0.12065 0.3048)
			(end -0.67945 0.3048)
			(stroke
				(width 0.1)
				(type default)
			)
			(layer "F.Fab")
		)
		(fp_line
			(start 0.120396 0.3048)
			(end 0.120396 0.2794)
			(stroke
				(width 0.1)
				(type default)
			)
			(layer "F.Fab")
		)
		(fp_line
			(start 0.67945 0.3048)
			(end 0.120396 0.3048)
			(stroke
				(width 0.1)
				(type default)
			)
			(layer "F.Fab")
		)
		(fp_line
			(start -0.12065 0.2794)
			(end -0.12065 0.3048)
			(stroke
				(width 0.1)
				(type default)
			)
			(layer "F.Fab")
		)
		(fp_line
			(start 0.120396 0.2794)
			(end -0.12065 0.2794)
			(stroke
				(width 0.1)
				(type default)
			)
			(layer "F.Fab")
		)
		(fp_line
			(start -0.12065 -0.2794)
			(end 0.12065 -0.2794)
			(stroke
				(width 0.1)
				(type default)
			)
			(layer "F.Fab")
		)
		(fp_line
			(start 0.12065 -0.2794)
			(end 0.12065 -0.3048)
			(stroke
				(width 0.1)
				(type default)
			)
			(layer "F.Fab")
		)
		(fp_line
			(start 0.12065 -0.3048)
			(end 0.67945 -0.3048)
			(stroke
				(width 0.1)
				(type default)
			)
			(layer "F.Fab")
		)
		(fp_line
			(start 0.67945 -0.3048)
			(end 0.67945 0.3048)
			(stroke
				(width 0.1)
				(type default)
			)
			(layer "F.Fab")
		)
		(fp_line
			(start -0.67945 -0.305054)
			(end -0.12065 -0.305054)
			(stroke
				(width 0.1)
				(type default)
			)
			(layer "F.Fab")
		)
		(fp_line
			(start -0.12065 -0.305054)
			(end -0.12065 -0.2794)
			(stroke
				(width 0.1)
				(type default)
			)
			(layer "F.Fab")
		)
		(pad "1" smd circle
			(at -0.40005 0 270)
			(size 0 0)
			(layers "F.Cu" "F.Mask" "F.Paste")
			(net "P0V8_PEX1_LSET1")
		)
		(pad "2" smd circle
			(at 0.40005 0 270)
			(size 0 0)
			(layers "F.Cu" "F.Mask" "F.Paste")
			(net "GND")
		)
	)
	(footprint ""
		(layer "F.Cu")
		(at 13.137896 -272.481294 180)
		(property "Reference" "R777"
			(at 0 0 180)
			(layer "F.SilkS")
			(hide yes)
			(effects
				(font
					(size 1.27 1.27)
				)
			)
		)
		(property "Value" ""
			(at 0 0 180)
			(layer "F.Fab")
			(effects
				(font
					(size 1.27 1.27)
				)
			)
		)
		(duplicate_pad_numbers_are_jumpers no)
		(fp_line
			(start 0.7874 0.4064)
			(end -0.7874 0.4064)
			(stroke
				(width 0.1524)
				(type default)
			)
			(layer "F.SilkS")
		)
		(fp_line
			(start 0.7874 -0.4064)
			(end 0.7874 0.4064)
			(stroke
				(width 0.1524)
				(type default)
			)
			(layer "F.SilkS")
		)
		(fp_line
			(start -0.7874 0.4064)
			(end -0.7874 -0.4064)
			(stroke
				(width 0.1524)
				(type default)
			)
			(layer "F.SilkS")
		)
		(fp_line
			(start -0.7874 -0.4064)
			(end 0.7874 -0.4064)
			(stroke
				(width 0.1524)
				(type default)
			)
			(layer "F.SilkS")
		)
		(fp_line
			(start 0.67945 0.3048)
			(end 0.120396 0.3048)
			(stroke
				(width 0.1)
				(type default)
			)
			(layer "F.Fab")
		)
		(fp_line
			(start 0.67945 -0.3048)
			(end 0.67945 0.3048)
			(stroke
				(width 0.1)
				(type default)
			)
			(layer "F.Fab")
		)
		(fp_line
			(start 0.12065 -0.2794)
			(end 0.12065 -0.3048)
			(stroke
				(width 0.1)
				(type default)
			)
			(layer "F.Fab")
		)
		(fp_line
			(start 0.12065 -0.3048)
			(end 0.67945 -0.3048)
			(stroke
				(width 0.1)
				(type default)
			)
			(layer "F.Fab")
		)
		(fp_line
			(start 0.120396 0.3048)
			(end 0.120396 0.2794)
			(stroke
				(width 0.1)
				(type default)
			)
			(layer "F.Fab")
		)
		(fp_line
			(start 0.120396 0.2794)
			(end -0.12065 0.2794)
			(stroke
				(width 0.1)
				(type default)
			)
			(layer "F.Fab")
		)
		(fp_line
			(start -0.12065 0.3048)
			(end -0.67945 0.3048)
			(stroke
				(width 0.1)
				(type default)
			)
			(layer "F.Fab")
		)
		(fp_line
			(start -0.12065 0.2794)
			(end -0.12065 0.3048)
			(stroke
				(width 0.1)
				(type default)
			)
			(layer "F.Fab")
		)
		(fp_line
			(start -0.12065 -0.2794)
			(end 0.12065 -0.2794)
			(stroke
				(width 0.1)
				(type default)
			)
			(layer "F.Fab")
		)
		(fp_line
			(start -0.12065 -0.305054)
			(end -0.12065 -0.2794)
			(stroke
				(width 0.1)
				(type default)
			)
			(layer "F.Fab")
		)
		(fp_line
			(start -0.67945 0.3048)
			(end -0.67945 -0.305054)
			(stroke
				(width 0.1)
				(type default)
			)
			(layer "F.Fab")
		)
		(fp_line
			(start -0.67945 -0.305054)
			(end -0.12065 -0.305054)
			(stroke
				(width 0.1)
				(type default)
			)
			(layer "F.Fab")
		)
		(pad "1" smd circle
			(at -0.40005 0 180)
			(size 0 0)
			(layers "F.Cu" "F.Mask" "F.Paste")
			(net "P1V25_PEX0_R")
		)
		(pad "2" smd circle
			(at 0.40005 0 180)
			(size 0 0)
			(layers "F.Cu" "F.Mask" "F.Paste")
			(net "P12V_PEX0_P1V25_VIN_P")
		)
	)
	(footprint ""
		(layer "F.Cu")
		(at 323.917818 -222.119698 180)
		(property "Reference" "R2981"
			(at 0 0 180)
			(layer "F.SilkS")
			(hide yes)
			(effects
				(font
					(size 1.27 1.27)
				)
			)
		)
		(property "Value" ""
			(at 0 0 180)
			(layer "F.Fab")
			(effects
				(font
					(size 1.27 1.27)
				)
			)
		)
		(duplicate_pad_numbers_are_jumpers no)
		(fp_line
			(start 0.7874 0.4064)
			(end -0.7874 0.4064)
			(stroke
				(width 0.1524)
				(type default)
			)
			(layer "F.SilkS")
		)
		(fp_line
			(start 0.7874 -0.4064)
			(end 0.7874 0.4064)
			(stroke
				(width 0.1524)
				(type default)
			)
			(layer "F.SilkS")
		)
		(fp_line
			(start -0.7874 0.4064)
			(end -0.7874 -0.4064)
			(stroke
				(width 0.1524)
				(type default)
			)
			(layer "F.SilkS")
		)
		(fp_line
			(start -0.7874 -0.4064)
			(end 0.7874 -0.4064)
			(stroke
				(width 0.1524)
				(type default)
			)
			(layer "F.SilkS")
		)
		(fp_line
			(start 0.67945 0.3048)
			(end 0.120396 0.3048)
			(stroke
				(width 0.1)
				(type default)
			)
			(layer "F.Fab")
		)
		(fp_line
			(start 0.67945 -0.3048)
			(end 0.67945 0.3048)
			(stroke
				(width 0.1)
				(type default)
			)
			(layer "F.Fab")
		)
		(fp_line
			(start 0.12065 -0.2794)
			(end 0.12065 -0.3048)
			(stroke
				(width 0.1)
				(type default)
			)
			(layer "F.Fab")
		)
		(fp_line
			(start 0.12065 -0.3048)
			(end 0.67945 -0.3048)
			(stroke
				(width 0.1)
				(type default)
			)
			(layer "F.Fab")
		)
		(fp_line
			(start 0.120396 0.3048)
			(end 0.120396 0.2794)
			(stroke
				(width 0.1)
				(type default)
			)
			(layer "F.Fab")
		)
		(fp_line
			(start 0.120396 0.2794)
			(end -0.12065 0.2794)
			(stroke
				(width 0.1)
				(type default)
			)
			(layer "F.Fab")
		)
		(fp_line
			(start -0.12065 0.3048)
			(end -0.67945 0.3048)
			(stroke
				(width 0.1)
				(type default)
			)
			(layer "F.Fab")
		)
		(fp_line
			(start -0.12065 0.2794)
			(end -0.12065 0.3048)
			(stroke
				(width 0.1)
				(type default)
			)
			(layer "F.Fab")
		)
		(fp_line
			(start -0.12065 -0.2794)
			(end 0.12065 -0.2794)
			(stroke
				(width 0.1)
				(type default)
			)
			(layer "F.Fab")
		)
		(fp_line
			(start -0.12065 -0.305054)
			(end -0.12065 -0.2794)
			(stroke
				(width 0.1)
				(type default)
			)
			(layer "F.Fab")
		)
		(fp_line
			(start -0.67945 0.3048)
			(end -0.67945 -0.305054)
			(stroke
				(width 0.1)
				(type default)
			)
			(layer "F.Fab")
		)
		(fp_line
			(start -0.67945 -0.305054)
			(end -0.12065 -0.305054)
			(stroke
				(width 0.1)
				(type default)
			)
			(layer "F.Fab")
		)
		(pad "1" smd circle
			(at -0.40005 0 180)
			(size 0 0)
			(layers "F.Cu" "F.Mask" "F.Paste")
			(net "LED_POSTCODE_3")
		)
		(pad "2" smd circle
			(at 0.40005 0 180)
			(size 0 0)
			(layers "F.Cu" "F.Mask" "F.Paste")
			(net "LED_POSTCODE_R_3")
		)
	)
	(footprint ""
		(layer "F.Cu")
		(at 232.46969 -82.518758 90)
		(property "Reference" "R6604"
			(at 0 0 90)
			(layer "F.SilkS")
			(hide yes)
			(effects
				(font
					(size 1.27 1.27)
				)
			)
		)
		(property "Value" ""
			(at 0 0 90)
			(layer "F.Fab")
			(effects
				(font
					(size 1.27 1.27)
				)
			)
		)
		(duplicate_pad_numbers_are_jumpers no)
		(fp_line
			(start 0.7874 -0.4064)
			(end 0.7874 0.4064)
			(stroke
				(width 0.1524)
				(type default)
			)
			(layer "F.SilkS")
		)
		(fp_line
			(start -0.7874 -0.4064)
			(end 0.7874 -0.4064)
			(stroke
				(width 0.1524)
				(type default)
			)
			(layer "F.SilkS")
		)
		(fp_line
			(start 0.007112 0.4064)
			(end -0.7874 0.4064)
			(stroke
				(width 0.1524)
				(type default)
			)
			(layer "F.SilkS")
		)
		(fp_line
			(start -0.12065 -0.305054)
			(end -0.12065 -0.2794)
			(stroke
				(width 0.1)
				(type default)
			)
			(layer "F.Fab")
		)
		(fp_line
			(start -0.67945 -0.305054)
			(end -0.12065 -0.305054)
			(stroke
				(width 0.1)
				(type default)
			)
			(layer "F.Fab")
		)
		(fp_line
			(start 0.67945 -0.3048)
			(end 0.67945 0.3048)
			(stroke
				(width 0.1)
				(type default)
			)
			(layer "F.Fab")
		)
		(fp_line
			(start 0.12065 -0.3048)
			(end 0.67945 -0.3048)
			(stroke
				(width 0.1)
				(type default)
			)
			(layer "F.Fab")
		)
		(fp_line
			(start 0.12065 -0.2794)
			(end 0.12065 -0.3048)
			(stroke
				(width 0.1)
				(type default)
			)
			(layer "F.Fab")
		)
		(fp_line
			(start -0.12065 -0.2794)
			(end 0.12065 -0.2794)
			(stroke
				(width 0.1)
				(type default)
			)
			(layer "F.Fab")
		)
		(fp_line
			(start 0.120396 0.2794)
			(end -0.12065 0.2794)
			(stroke
				(width 0.1)
				(type default)
			)
			(layer "F.Fab")
		)
		(fp_line
			(start -0.12065 0.2794)
			(end -0.12065 0.3048)
			(stroke
				(width 0.1)
				(type default)
			)
			(layer "F.Fab")
		)
		(fp_line
			(start 0.67945 0.3048)
			(end 0.120396 0.3048)
			(stroke
				(width 0.1)
				(type default)
			)
			(layer "F.Fab")
		)
		(fp_line
			(start 0.120396 0.3048)
			(end 0.120396 0.2794)
			(stroke
				(width 0.1)
				(type default)
			)
			(layer "F.Fab")
		)
		(fp_line
			(start -0.12065 0.3048)
			(end -0.67945 0.3048)
			(stroke
				(width 0.1)
				(type default)
			)
			(layer "F.Fab")
		)
		(fp_line
			(start -0.67945 0.3048)
			(end -0.67945 -0.305054)
			(stroke
				(width 0.1)
				(type default)
			)
			(layer "F.Fab")
		)
		(pad "1" smd rect
			(at -0.40005 0 270)
			(size 0.4572 0.508)
			(layers "F.Cu" "F.Mask" "F.Paste")
			(net "USB2_CP2108_SDB_DN")
		)
		(pad "2" smd rect
			(at 0.40005 0 270)
			(size 0.4572 0.508)
			(layers "F.Cu" "F.Mask" "F.Paste")
			(net "USB2_FT4232_SDB_R_DN")
		)
	)
	(footprint ""
		(layer "F.Cu")
		(at 217.767916 -18.437098)
		(property "Reference" "R1680"
			(at 0 0 0)
			(layer "F.SilkS")
			(hide yes)
			(effects
				(font
					(size 1.27 1.27)
				)
			)
		)
		(property "Value" ""
			(at 0 0 0)
			(layer "F.Fab")
			(effects
				(font
					(size 1.27 1.27)
				)
			)
		)
		(duplicate_pad_numbers_are_jumpers no)
		(fp_line
			(start -0.7874 -0.4064)
			(end 0.7874 -0.4064)
			(stroke
				(width 0.1524)
				(type default)
			)
			(layer "F.SilkS")
		)
		(fp_line
			(start -0.7874 0.4064)
			(end -0.7874 -0.4064)
			(stroke
				(width 0.1524)
				(type default)
			)
			(layer "F.SilkS")
		)
		(fp_line
			(start 0.7874 -0.4064)
			(end 0.7874 0.4064)
			(stroke
				(width 0.1524)
				(type default)
			)
			(layer "F.SilkS")
		)
		(fp_line
			(start 0.7874 0.4064)
			(end -0.7874 0.4064)
			(stroke
				(width 0.1524)
				(type default)
			)
			(layer "F.SilkS")
		)
		(fp_line
			(start -0.67945 -0.305054)
			(end -0.12065 -0.305054)
			(stroke
				(width 0.1)
				(type default)
			)
			(layer "F.Fab")
		)
		(fp_line
			(start -0.67945 0.3048)
			(end -0.67945 -0.305054)
			(stroke
				(width 0.1)
				(type default)
			)
			(layer "F.Fab")
		)
		(fp_line
			(start -0.12065 -0.305054)
			(end -0.12065 -0.2794)
			(stroke
				(width 0.1)
				(type default)
			)
			(layer "F.Fab")
		)
		(fp_line
			(start -0.12065 -0.2794)
			(end 0.12065 -0.2794)
			(stroke
				(width 0.1)
				(type default)
			)
			(layer "F.Fab")
		)
		(fp_line
			(start -0.12065 0.2794)
			(end -0.12065 0.3048)
			(stroke
				(width 0.1)
				(type default)
			)
			(layer "F.Fab")
		)
		(fp_line
			(start -0.12065 0.3048)
			(end -0.67945 0.3048)
			(stroke
				(width 0.1)
				(type default)
			)
			(layer "F.Fab")
		)
		(fp_line
			(start 0.120396 0.2794)
			(end -0.12065 0.2794)
			(stroke
				(width 0.1)
				(type default)
			)
			(layer "F.Fab")
		)
		(fp_line
			(start 0.120396 0.3048)
			(end 0.120396 0.2794)
			(stroke
				(width 0.1)
				(type default)
			)
			(layer "F.Fab")
		)
		(fp_line
			(start 0.12065 -0.3048)
			(end 0.67945 -0.3048)
			(stroke
				(width 0.1)
				(type default)
			)
			(layer "F.Fab")
		)
		(fp_line
			(start 0.12065 -0.2794)
			(end 0.12065 -0.3048)
			(stroke
				(width 0.1)
				(type default)
			)
			(layer "F.Fab")
		)
		(fp_line
			(start 0.67945 -0.3048)
			(end 0.67945 0.3048)
			(stroke
				(width 0.1)
				(type default)
			)
			(layer "F.Fab")
		)
		(fp_line
			(start 0.67945 0.3048)
			(end 0.120396 0.3048)
			(stroke
				(width 0.1)
				(type default)
			)
			(layer "F.Fab")
		)
		(pad "1" smd circle
			(at -0.40005 0)
			(size 0 0)
			(layers "F.Cu" "F.Mask" "F.Paste")
			(net "SMB_ISO_SSD7_R_SCL")
		)
		(pad "2" smd circle
			(at 0.40005 0)
			(size 0 0)
			(layers "F.Cu" "F.Mask" "F.Paste")
			(net "SMB_ISO_SSD7_SCL")
		)
	)
	(footprint ""
		(layer "F.Cu")
		(at 301.822612 -22.867366 90)
		(property "Reference" "C3945"
			(at 0 0 90)
			(layer "F.SilkS")
			(hide yes)
			(effects
				(font
					(size 1.27 1.27)
				)
			)
		)
		(property "Value" ""
			(at 0 0 90)
			(layer "F.Fab")
			(effects
				(font
					(size 1.27 1.27)
				)
			)
		)
		(duplicate_pad_numbers_are_jumpers no)
		(fp_line
			(start 0.7874 -0.4064)
			(end 0.7874 0.4064)
			(stroke
				(width 0.1524)
				(type default)
			)
			(layer "F.SilkS")
		)
		(fp_line
			(start -0.7874 -0.4064)
			(end 0.7874 -0.4064)
			(stroke
				(width 0.1524)
				(type default)
			)
			(layer "F.SilkS")
		)
		(fp_line
			(start 0.7874 0.4064)
			(end -0.7874 0.4064)
			(stroke
				(width 0.1524)
				(type default)
			)
			(layer "F.SilkS")
		)
		(fp_line
			(start -0.7874 0.4064)
			(end -0.7874 -0.4064)
			(stroke
				(width 0.1524)
				(type default)
			)
			(layer "F.SilkS")
		)
		(fp_line
			(start -0.12065 -0.305054)
			(end -0.12065 -0.2794)
			(stroke
				(width 0.1)
				(type default)
			)
			(layer "F.Fab")
		)
		(fp_line
			(start -0.67945 -0.305054)
			(end -0.12065 -0.305054)
			(stroke
				(width 0.1)
				(type default)
			)
			(layer "F.Fab")
		)
		(fp_line
			(start 0.67945 -0.3048)
			(end 0.67945 0.3048)
			(stroke
				(width 0.1)
				(type default)
			)
			(layer "F.Fab")
		)
		(fp_line
			(start 0.12065 -0.3048)
			(end 0.67945 -0.3048)
			(stroke
				(width 0.1)
				(type default)
			)
			(layer "F.Fab")
		)
		(fp_line
			(start 0.12065 -0.2794)
			(end 0.12065 -0.3048)
			(stroke
				(width 0.1)
				(type default)
			)
			(layer "F.Fab")
		)
		(fp_line
			(start -0.12065 -0.2794)
			(end 0.12065 -0.2794)
			(stroke
				(width 0.1)
				(type default)
			)
			(layer "F.Fab")
		)
		(fp_line
			(start 0.120396 0.2794)
			(end -0.12065 0.2794)
			(stroke
				(width 0.1)
				(type default)
			)
			(layer "F.Fab")
		)
		(fp_line
			(start -0.12065 0.2794)
			(end -0.12065 0.3048)
			(stroke
				(width 0.1)
				(type default)
			)
			(layer "F.Fab")
		)
		(fp_line
			(start 0.67945 0.3048)
			(end 0.120396 0.3048)
			(stroke
				(width 0.1)
				(type default)
			)
			(layer "F.Fab")
		)
		(fp_line
			(start 0.120396 0.3048)
			(end 0.120396 0.2794)
			(stroke
				(width 0.1)
				(type default)
			)
			(layer "F.Fab")
		)
		(fp_line
			(start -0.12065 0.3048)
			(end -0.67945 0.3048)
			(stroke
				(width 0.1)
				(type default)
			)
			(layer "F.Fab")
		)
		(fp_line
			(start -0.67945 0.3048)
			(end -0.67945 -0.305054)
			(stroke
				(width 0.1)
				(type default)
			)
			(layer "F.Fab")
		)
		(pad "1" smd circle
			(at -0.40005 0 90)
			(size 0 0)
			(layers "F.Cu" "F.Mask" "F.Paste")
			(net "P12V_SSD10")
		)
		(pad "2" smd circle
			(at 0.40005 0 90)
			(size 0 0)
			(layers "F.Cu" "F.Mask" "F.Paste")
			(net "GND")
		)
	)
)
